# S9S_MB_2U (Grand Teton) — schematic netlist excerpt (pin names and nets, part order shuffled) for the footprints in the layout excerpt that follows; sources: Cadence DE-HDL packaged netlist, KiCad conversion of 03242023_DA0F0TMBIJ0_F0T_Motherboard_J_brd_V01_OCP.brd

PL29  Q_INDUCTOR4P_14  150NH IND  pkg L_TLM117513Q-151QL_11X7-5XA  page 286
  \1\  = SW_PVCCIN_CPU1_SW3
  \2\  = IND_P1_CPL3
  \3\  = IND_P1_CPL2
  \4\  = PVCCIN_CPU1

R3778  Q_RES  0 5% CHIP  pkg 0402LF  page 240 : A = FM_SOL_UART_CH_SEL_R ; B = FM_SOL_UART_CH_SEL

(kicad_pcb
	(version 20260206)
	(generator "pcbnew")
	(generator_version "10.0")
	(general
		(thickness 1.6)
		(legacy_teardrops no)
	)
	(paper "A4")
	(title_block
		(title "03242023_DA0F0TMBIJ0_F0T_Motherboard_J_brd_V01_OCP.brd")
		(comment 1 "Grand Teton / footprints 3531-3532 of 6105")
	)
	(layers
		(0 "F.Cu" signal "TOP")
		(4 "In1.Cu" signal "GND")
		(6 "In2.Cu" signal "IN1")
		(8 "In3.Cu" signal "GND1")
		(10 "In4.Cu" signal "IN2")
		(12 "In5.Cu" signal "GND2")
		(14 "In6.Cu" signal "IN3")
		(16 "In7.Cu" signal "GND3")
		(18 "In8.Cu" signal "VCC")
		(20 "In9.Cu" signal "VCC1")
		(22 "In10.Cu" signal "GND4")
		(24 "In11.Cu" signal "IN4")
		(26 "In12.Cu" signal "GND5")
		(28 "In13.Cu" signal "IN5")
		(30 "In14.Cu" signal "GND6")
		(32 "In15.Cu" signal "IN6")
		(34 "In16.Cu" signal "GND7")
		(2 "B.Cu" signal "BOTTOM")
		(9 "F.Adhes" user "F.Adhesive")
		(11 "B.Adhes" user "B.Adhesive")
		(13 "F.Paste" user "Package Geometry/Pastemask Top")
		(15 "B.Paste" user "Package Geometry/Pastemask Bottom")
		(5 "F.SilkS" user "Ref Des/Silkscreen Top")
		(7 "B.SilkS" user "Ref Des/Silkscreen Bottom")
		(1 "F.Mask" user "Board Geometry/Soldermask Top")
		(3 "B.Mask" user "Board Geometry/Soldermask Bottom")
		(17 "Dwgs.User" user "User.Drawings")
		(19 "Cmts.User" user "User.Comments")
		(21 "Eco1.User" user "User.Eco1")
		(23 "Eco2.User" user "User.Eco2")
		(25 "Edge.Cuts" user "Board Geometry/Outline")
		(27 "Margin" user)
		(31 "F.CrtYd" user "Package Geometry/Place Bound Top")
		(29 "B.CrtYd" user "Package Geometry/Place Bound Bottom")
		(35 "F.Fab" user "Ref Des/Assembly Top")
		(33 "B.Fab" user "Ref Des/Assembly Bottom")
	)
	(footprint ""
		(layer "F.Cu")
		(at 113.349024 -324.445376)
		(property "Reference" "PL29"
			(at 15.954756 6.788658 0)
			(unlocked yes)
			(layer "F.SilkS")
			(effects
				(font
					(size 0.7874 0.5842)
					(thickness 0.1524)
				)
				(justify left)
			)
		)
		(property "Value" ""
			(at 0 0 0)
			(layer "F.Fab")
			(effects
				(font
					(size 1.27 1.27)
				)
			)
		)
		(duplicate_pad_numbers_are_jumpers no)
		(fp_line
			(start -3.750056 -5.500116)
			(end -2.393442 -5.500116)
			(stroke
				(width 0.1524)
				(type default)
			)
			(layer "F.SilkS")
		)
		(fp_line
			(start -3.750056 5.500116)
			(end -3.750056 -5.500116)
			(stroke
				(width 0.1524)
				(type default)
			)
			(layer "F.SilkS")
		)
		(fp_line
			(start -2.393442 5.500116)
			(end -3.750056 5.500116)
			(stroke
				(width 0.1524)
				(type default)
			)
			(layer "F.SilkS")
		)
		(fp_line
			(start 2.393442 5.500116)
			(end 3.750056 5.500116)
			(stroke
				(width 0.1524)
				(type default)
			)
			(layer "F.SilkS")
		)
		(fp_line
			(start 3.750056 -5.500116)
			(end 2.393442 -5.500116)
			(stroke
				(width 0.1524)
				(type default)
			)
			(layer "F.SilkS")
		)
		(fp_line
			(start 3.750056 5.500116)
			(end 3.750056 -5.500116)
			(stroke
				(width 0.1524)
				(type default)
			)
			(layer "F.SilkS")
		)
		(fp_poly
			(pts
				(xy -3.554476 -7.016496) (xy -3.19532 -5.938774) (xy -4.273042 -6.29793)
			)
			(stroke
				(width 0)
				(type default)
			)
			(fill yes)
			(layer "F.SilkS")
		)
		(fp_line
			(start -3.750056 -5.500116)
			(end -3.750056 5.500116)
			(stroke
				(width 0.1)
				(type default)
			)
			(layer "F.Fab")
		)
		(fp_line
			(start -3.750056 5.500116)
			(end 3.750056 5.500116)
			(stroke
				(width 0.1)
				(type default)
			)
			(layer "F.Fab")
		)
		(fp_line
			(start 3.750056 -5.500116)
			(end -3.750056 -5.500116)
			(stroke
				(width 0.1)
				(type default)
			)
			(layer "F.Fab")
		)
		(fp_line
			(start 3.750056 5.500116)
			(end 3.750056 -5.500116)
			(stroke
				(width 0.1)
				(type default)
			)
			(layer "F.Fab")
		)
		(fp_poly
			(pts
				(xy -4.9276 -4.757928) (xy -4.9276 -3.741928) (xy -3.9116 -4.249928)
			)
			(stroke
				(width 0)
				(type default)
			)
			(fill yes)
			(layer "F.Fab")
		)
		(pad "1" smd rect
			(at 0 -4.249928 270)
			(size 2.413 4.5212)
			(layers "F.Cu" "F.Mask" "F.Paste")
			(net "SW_PVCCIN_CPU1_SW3")
		)
		(pad "2" smd rect
			(at 0 -1.175004 270)
			(size 1.3716 4.5212)
			(layers "F.Cu" "F.Mask" "F.Paste")
			(net "IND_P1_CPL3")
		)
		(pad "3" smd rect
			(at 0 1.175004 270)
			(size 1.3716 4.5212)
			(layers "F.Cu" "F.Mask" "F.Paste")
			(net "IND_P1_CPL2")
		)
		(pad "4" smd rect
			(at 0 4.249928 270)
			(size 2.413 4.5212)
			(layers "F.Cu" "F.Mask" "F.Paste")
			(net "PVCCIN_CPU1")
		)
	)
	(footprint ""
		(layer "F.Cu")
		(at 149.68982 -22.73808 90)
		(property "Reference" "R3778"
			(at 0 0 90)
			(layer "F.SilkS")
			(hide yes)
			(effects
				(font
					(size 1.27 1.27)
				)
			)
		)
		(property "Value" ""
			(at 0 0 90)
			(layer "F.Fab")
			(effects
				(font
					(size 1.27 1.27)
				)
			)
		)
		(duplicate_pad_numbers_are_jumpers no)
		(fp_line
			(start 0.7874 -0.4064)
			(end 0.7874 0.4064)
			(stroke
				(width 0.1524)
				(type default)
			)
			(layer "F.SilkS")
		)
		(fp_line
			(start -0.7874 -0.4064)
			(end 0.7874 -0.4064)
			(stroke
				(width 0.1524)
				(type default)
			)
			(layer "F.SilkS")
		)
		(fp_line
			(start 0.7874 0.4064)
			(end -0.7874 0.4064)
			(stroke
				(width 0.1524)
				(type default)
			)
			(layer "F.SilkS")
		)
		(fp_line
			(start -0.7874 0.4064)
			(end -0.7874 -0.4064)
			(stroke
				(width 0.1524)
				(type default)
			)
			(layer "F.SilkS")
		)
		(fp_line
			(start -0.12065 -0.305054)
			(end -0.12065 -0.2794)
			(stroke
				(width 0.1)
				(type default)
			)
			(layer "F.Fab")
		)
		(fp_line
			(start -0.67945 -0.305054)
			(end -0.12065 -0.305054)
			(stroke
				(width 0.1)
				(type default)
			)
			(layer "F.Fab")
		)
		(fp_line
			(start 0.67945 -0.3048)
			(end 0.67945 0.3048)
			(stroke
				(width 0.1)
				(type default)
			)
			(layer "F.Fab")
		)
		(fp_line
			(start 0.12065 -0.3048)
			(end 0.67945 -0.3048)
			(stroke
				(width 0.1)
				(type default)
			)
			(layer "F.Fab")
		)
		(fp_line
			(start 0.12065 -0.2794)
			(end 0.12065 -0.3048)
			(stroke
				(width 0.1)
				(type default)
			)
			(layer "F.Fab")
		)
		(fp_line
			(start -0.12065 -0.2794)
			(end 0.12065 -0.2794)
			(stroke
				(width 0.1)
				(type default)
			)
			(layer "F.Fab")
		)
		(fp_line
			(start 0.120396 0.2794)
			(end -0.12065 0.2794)
			(stroke
				(width 0.1)
				(type default)
			)
			(layer "F.Fab")
		)
		(fp_line
			(start -0.12065 0.2794)
			(end -0.12065 0.3048)
			(stroke
				(width 0.1)
				(type default)
			)
			(layer "F.Fab")
		)
		(fp_line
			(start 0.67945 0.3048)
			(end 0.120396 0.3048)
			(stroke
				(width 0.1)
				(type default)
			)
			(layer "F.Fab")
		)
		(fp_line
			(start 0.120396 0.3048)
			(end 0.120396 0.2794)
			(stroke
				(width 0.1)
				(type default)
			)
			(layer "F.Fab")
		)
		(fp_line
			(start -0.12065 0.3048)
			(end -0.67945 0.3048)
			(stroke
				(width 0.1)
				(type default)
			)
			(layer "F.Fab")
		)
		(fp_line
			(start -0.67945 0.3048)
			(end -0.67945 -0.305054)
			(stroke
				(width 0.1)
				(type default)
			)
			(layer "F.Fab")
		)
		(pad "1" smd circle
			(at -0.40005 0 90)
			(size 0 0)
			(layers "F.Cu" "F.Mask" "F.Paste")
			(net "FM_SOL_UART_CH_SEL_R")
		)
		(pad "2" smd circle
			(at 0.40005 0 90)
			(size 0 0)
			(layers "F.Cu" "F.Mask" "F.Paste")
			(net "FM_SOL_UART_CH_SEL")
		)
	)
)
